# T6G (Grand Teton) — schematic netlist excerpt (pin names and nets, part order shuffled) for the footprints in the layout excerpt that follows; sources: Cadence DE-HDL packaged netlist, KiCad conversion of 04192023_DAF0TMB3IC0_F0TG_MB_C_brd_V02_OCP.brd

PC6554_1  Q_CAP  1UF 25V 10% X6S  pkg C0402  page 363 : A = SW_P12V_AUX_P0V9_RETIMER_CPU0_FLT ; B = GND
R630  Q_RES  51.1 1% EMPTY  pkg 0201LF  page 287 : A = CLK_100M_RETIMER_CPU0_P1_DP ; B = GND
R3106  Q_RES  0 5% CHIP  pkg 0402LF  page 248 : A = SMB_BMC_SWB_SDA ; B = SMB_BMC_SWB_R_SDA

(kicad_pcb
	(version 20260206)
	(generator "pcbnew")
	(generator_version "10.0")
	(general
		(thickness 1.6)
		(legacy_teardrops no)
	)
	(paper "A4")
	(title_block
		(title "04192023_DAF0TMB3IC0_F0TG_MB_C_brd_V02_OCP.brd")
		(comment 1 "Grand Teton / footprints 4699-4701 of 8354")
	)
	(layers
		(0 "F.Cu" signal "TOP")
		(4 "In1.Cu" signal "GND")
		(6 "In2.Cu" signal "IN1")
		(8 "In3.Cu" signal "GND1")
		(10 "In4.Cu" signal "IN2")
		(12 "In5.Cu" signal "GND2")
		(14 "In6.Cu" signal "IN3")
		(16 "In7.Cu" signal "GND3")
		(18 "In8.Cu" signal "VCC")
		(20 "In9.Cu" signal "VCC1")
		(22 "In10.Cu" signal "GND4")
		(24 "In11.Cu" signal "IN4")
		(26 "In12.Cu" signal "GND5")
		(28 "In13.Cu" signal "IN5")
		(30 "In14.Cu" signal "GND6")
		(32 "In15.Cu" signal "IN6")
		(34 "In16.Cu" signal "GND7")
		(2 "B.Cu" signal "BOTTOM")
		(9 "F.Adhes" user "F.Adhesive")
		(11 "B.Adhes" user "B.Adhesive")
		(13 "F.Paste" user "Package Geometry/Pastemask Top")
		(15 "B.Paste" user "Package Geometry/Pastemask Bottom")
		(5 "F.SilkS" user "Ref Des/Silkscreen Top")
		(7 "B.SilkS" user "Ref Des/Silkscreen Bottom")
		(1 "F.Mask" user "Board Geometry/Soldermask Top")
		(3 "B.Mask" user "Board Geometry/Soldermask Bottom")
		(17 "Dwgs.User" user "User.Drawings")
		(19 "Cmts.User" user "User.Comments")
		(21 "Eco1.User" user "User.Eco1")
		(23 "Eco2.User" user "User.Eco2")
		(25 "Edge.Cuts" user "Board Geometry/Outline")
		(27 "Margin" user)
		(31 "F.CrtYd" user "Package Geometry/Place Bound Top")
		(29 "B.CrtYd" user "Package Geometry/Place Bound Bottom")
		(35 "F.Fab" user "Ref Des/Assembly Top")
		(33 "B.Fab" user "Ref Des/Assembly Bottom")
	)
	(footprint ""
		(layer "F.Cu")
		(at 448.717924 -397.399002 -90)
		(property "Reference" "PC6554_1"
			(at 0 0 270)
			(layer "F.SilkS")
			(hide yes)
			(effects
				(font
					(size 1.27 1.27)
				)
			)
		)
		(property "Value" ""
			(at 0 0 270)
			(layer "F.Fab")
			(effects
				(font
					(size 1.27 1.27)
				)
			)
		)
		(duplicate_pad_numbers_are_jumpers no)
		(fp_line
			(start -0.7874 0.4064)
			(end -0.7874 -0.4064)
			(stroke
				(width 0.1524)
				(type default)
			)
			(layer "F.SilkS")
		)
		(fp_line
			(start 0.7874 0.4064)
			(end -0.7874 0.4064)
			(stroke
				(width 0.1524)
				(type default)
			)
			(layer "F.SilkS")
		)
		(fp_line
			(start -0.7874 -0.4064)
			(end 0.7874 -0.4064)
			(stroke
				(width 0.1524)
				(type default)
			)
			(layer "F.SilkS")
		)
		(fp_line
			(start 0.7874 -0.4064)
			(end 0.7874 0.4064)
			(stroke
				(width 0.1524)
				(type default)
			)
			(layer "F.SilkS")
		)
		(fp_line
			(start -0.67945 0.3048)
			(end -0.67945 -0.305054)
			(stroke
				(width 0.1)
				(type default)
			)
			(layer "F.Fab")
		)
		(fp_line
			(start -0.12065 0.3048)
			(end -0.67945 0.3048)
			(stroke
				(width 0.1)
				(type default)
			)
			(layer "F.Fab")
		)
		(fp_line
			(start 0.120396 0.3048)
			(end 0.120396 0.2794)
			(stroke
				(width 0.1)
				(type default)
			)
			(layer "F.Fab")
		)
		(fp_line
			(start 0.67945 0.3048)
			(end 0.120396 0.3048)
			(stroke
				(width 0.1)
				(type default)
			)
			(layer "F.Fab")
		)
		(fp_line
			(start -0.12065 0.2794)
			(end -0.12065 0.3048)
			(stroke
				(width 0.1)
				(type default)
			)
			(layer "F.Fab")
		)
		(fp_line
			(start 0.120396 0.2794)
			(end -0.12065 0.2794)
			(stroke
				(width 0.1)
				(type default)
			)
			(layer "F.Fab")
		)
		(fp_line
			(start -0.12065 -0.2794)
			(end 0.12065 -0.2794)
			(stroke
				(width 0.1)
				(type default)
			)
			(layer "F.Fab")
		)
		(fp_line
			(start 0.12065 -0.2794)
			(end 0.12065 -0.3048)
			(stroke
				(width 0.1)
				(type default)
			)
			(layer "F.Fab")
		)
		(fp_line
			(start 0.12065 -0.3048)
			(end 0.67945 -0.3048)
			(stroke
				(width 0.1)
				(type default)
			)
			(layer "F.Fab")
		)
		(fp_line
			(start 0.67945 -0.3048)
			(end 0.67945 0.3048)
			(stroke
				(width 0.1)
				(type default)
			)
			(layer "F.Fab")
		)
		(fp_line
			(start -0.67945 -0.305054)
			(end -0.12065 -0.305054)
			(stroke
				(width 0.1)
				(type default)
			)
			(layer "F.Fab")
		)
		(fp_line
			(start -0.12065 -0.305054)
			(end -0.12065 -0.2794)
			(stroke
				(width 0.1)
				(type default)
			)
			(layer "F.Fab")
		)
		(pad "1" smd circle
			(at -0.40005 0 270)
			(size 0 0)
			(layers "F.Cu" "F.Mask" "F.Paste")
			(net "SW_P12V_AUX_P0V9_RETIMER_CPU0_FLT")
		)
		(pad "2" smd circle
			(at 0.40005 0 270)
			(size 0 0)
			(layers "F.Cu" "F.Mask" "F.Paste")
			(net "GND")
		)
	)
	(footprint ""
		(layer "F.Cu")
		(at 166.3192 -433.878736 180)
		(property "Reference" "R3106"
			(at 0 0 180)
			(layer "F.SilkS")
			(hide yes)
			(effects
				(font
					(size 1.27 1.27)
				)
			)
		)
		(property "Value" ""
			(at 0 0 180)
			(layer "F.Fab")
			(effects
				(font
					(size 1.27 1.27)
				)
			)
		)
		(duplicate_pad_numbers_are_jumpers no)
		(fp_line
			(start 0.7874 0.4064)
			(end -0.7874 0.4064)
			(stroke
				(width 0.1524)
				(type default)
			)
			(layer "F.SilkS")
		)
		(fp_line
			(start 0.7874 -0.4064)
			(end 0.7874 0.4064)
			(stroke
				(width 0.1524)
				(type default)
			)
			(layer "F.SilkS")
		)
		(fp_line
			(start -0.7874 0.4064)
			(end -0.7874 -0.4064)
			(stroke
				(width 0.1524)
				(type default)
			)
			(layer "F.SilkS")
		)
		(fp_line
			(start -0.7874 -0.4064)
			(end 0.7874 -0.4064)
			(stroke
				(width 0.1524)
				(type default)
			)
			(layer "F.SilkS")
		)
		(fp_line
			(start 0.67945 0.3048)
			(end 0.120396 0.3048)
			(stroke
				(width 0.1)
				(type default)
			)
			(layer "F.Fab")
		)
		(fp_line
			(start 0.67945 -0.3048)
			(end 0.67945 0.3048)
			(stroke
				(width 0.1)
				(type default)
			)
			(layer "F.Fab")
		)
		(fp_line
			(start 0.12065 -0.2794)
			(end 0.12065 -0.3048)
			(stroke
				(width 0.1)
				(type default)
			)
			(layer "F.Fab")
		)
		(fp_line
			(start 0.12065 -0.3048)
			(end 0.67945 -0.3048)
			(stroke
				(width 0.1)
				(type default)
			)
			(layer "F.Fab")
		)
		(fp_line
			(start 0.120396 0.3048)
			(end 0.120396 0.2794)
			(stroke
				(width 0.1)
				(type default)
			)
			(layer "F.Fab")
		)
		(fp_line
			(start 0.120396 0.2794)
			(end -0.12065 0.2794)
			(stroke
				(width 0.1)
				(type default)
			)
			(layer "F.Fab")
		)
		(fp_line
			(start -0.12065 0.3048)
			(end -0.67945 0.3048)
			(stroke
				(width 0.1)
				(type default)
			)
			(layer "F.Fab")
		)
		(fp_line
			(start -0.12065 0.2794)
			(end -0.12065 0.3048)
			(stroke
				(width 0.1)
				(type default)
			)
			(layer "F.Fab")
		)
		(fp_line
			(start -0.12065 -0.2794)
			(end 0.12065 -0.2794)
			(stroke
				(width 0.1)
				(type default)
			)
			(layer "F.Fab")
		)
		(fp_line
			(start -0.12065 -0.305054)
			(end -0.12065 -0.2794)
			(stroke
				(width 0.1)
				(type default)
			)
			(layer "F.Fab")
		)
		(fp_line
			(start -0.67945 0.3048)
			(end -0.67945 -0.305054)
			(stroke
				(width 0.1)
				(type default)
			)
			(layer "F.Fab")
		)
		(fp_line
			(start -0.67945 -0.305054)
			(end -0.12065 -0.305054)
			(stroke
				(width 0.1)
				(type default)
			)
			(layer "F.Fab")
		)
		(pad "1" smd circle
			(at -0.40005 0 180)
			(size 0 0)
			(layers "F.Cu" "F.Mask" "F.Paste")
			(net "SMB_BMC_SWB_SDA")
		)
		(pad "2" smd circle
			(at 0.40005 0 180)
			(size 0 0)
			(layers "F.Cu" "F.Mask" "F.Paste")
			(net "SMB_BMC_SWB_R_SDA")
		)
	)
	(footprint ""
		(layer "F.Cu")
		(at 332.071472 -396.412974 90)
		(property "Reference" "R630"
			(at 0 0 90)
			(layer "F.SilkS")
			(hide yes)
			(effects
				(font
					(size 1.27 1.27)
				)
			)
		)
		(property "Value" ""
			(at 0 0 90)
			(layer "F.Fab")
			(effects
				(font
					(size 1.27 1.27)
				)
			)
		)
		(duplicate_pad_numbers_are_jumpers no)
		(fp_line
			(start 0.32512 -0.175006)
			(end 0.32512 0.175006)
			(stroke
				(width 0.1)
				(type default)
			)
			(layer "F.Fab")
		)
		(fp_line
			(start -0.32512 -0.175006)
			(end 0.32512 -0.175006)
			(stroke
				(width 0.1)
				(type default)
			)
			(layer "F.Fab")
		)
		(fp_line
			(start 0.32512 0.175006)
			(end -0.32512 0.175006)
			(stroke
				(width 0.1)
				(type default)
			)
			(layer "F.Fab")
		)
		(fp_line
			(start -0.32512 0.175006)
			(end -0.32512 -0.175006)
			(stroke
				(width 0.1)
				(type default)
			)
			(layer "F.Fab")
		)
		(pad "1" smd rect
			(at -0.2667 0 90)
			(size 0.3048 0.381)
			(layers "F.Cu" "F.Mask" "F.Paste")
			(net "CLK_100M_RETIMER_CPU0_P1_DP")
		)
		(pad "2" smd rect
			(at 0.2667 0 270)
			(size 0.3048 0.381)
			(layers "F.Cu" "F.Mask" "F.Paste")
			(net "GND")
		)
	)
)
